# T6G (Grand Teton) — schematic parts with pin connectivity, parts 2652–2654 of 8303; source: Cadence DE-HDL packaged netlist (pstxprt.dat, pstxnet.dat, pstchip.dat)

J106  CONN112_10137002101LF  CONN112_10137002-101LF IO  pkg HSD_F112D8_P2W1-2_RDH  page 116
  A1  A1  BI  = PRSNT_CABLE_SWB_B1_N
  A2  A2  BI  = GND
  A3  A3  BI  = FM_SWB_PWRGD
  A4  A4  BI  = GND
  A5  A5  BI  = NC_J106_A5
  A6  A6  BI  = GND
  A7  A7  BI  = PRSNT_CABLE_GPU_A1_N
  A8  A8  BI  = GND
  B1  B1  BI  = GND
  B2  B2  BI  = P5E_CPU0_P2_RX_BUF_DN<1>
  B3  B3  BI  = GND
  B4  B4  BI  = P5E_CPU0_P2_RX_BUF_DN<3>
  B5  B5  BI  = GND
  B6  B6  BI  = P5E_CPU0_P2_RX_BUF_DN<5>
  B7  B7  BI  = GND
  B8  B8  BI  = P5E_CPU0_P2_RX_BUF_DN<7>
  C1  C1  BI  = P5E_CPU0_P2_RX_BUF_DN<0>
  C2  C2  BI  = P5E_CPU0_P2_RX_BUF_DP<1>
  C3  C3  BI  = P5E_CPU0_P2_RX_BUF_DN<2>
  C4  C4  BI  = P5E_CPU0_P2_RX_BUF_DP<3>
  C5  C5  BI  = P5E_CPU0_P2_RX_BUF_DN<4>
  C6  C6  BI  = P5E_CPU0_P2_RX_BUF_DP<5>
  C7  C7  BI  = P5E_CPU0_P2_RX_BUF_DN<6>
  C8  C8  BI  = P5E_CPU0_P2_RX_BUF_DP<7>
  D1  D1  BI  = P5E_CPU0_P2_RX_BUF_DP<0>
  D2  D2  BI  = GND
  D3  D3  BI  = P5E_CPU0_P2_RX_BUF_DP<2>
  D4  D4  BI  = GND
  D5  D5  BI  = P5E_CPU0_P2_RX_BUF_DP<4>
  D6  D6  BI  = GND
  D7  D7  BI  = P5E_CPU0_P2_RX_BUF_DP<6>
  D8  D8  BI  = GND
  E1  E1  BI  = GND
  E2  E2  BI  = P5E_CPU0_P3_RX_BUF_DN<1>
  E3  E3  BI  = GND
  E4  E4  BI  = P5E_CPU0_P3_RX_BUF_DN<3>
  E5  E5  BI  = GND
  E6  E6  BI  = P5E_CPU0_P3_RX_BUF_DN<5>
  E7  E7  BI  = GND
  E8  E8  BI  = P5E_CPU0_P3_RX_BUF_DN<7>
  F1  F1  BI  = P5E_CPU0_P3_RX_BUF_DN<0>
  F2  F2  BI  = P5E_CPU0_P3_RX_BUF_DP<1>
  F3  F3  BI  = P5E_CPU0_P3_RX_BUF_DN<2>
  F4  F4  BI  = P5E_CPU0_P3_RX_BUF_DP<3>
  F5  F5  BI  = P5E_CPU0_P3_RX_BUF_DN<4>
  F6  F6  BI  = P5E_CPU0_P3_RX_BUF_DP<5>
  F7  F7  BI  = P5E_CPU0_P3_RX_BUF_DN<6>
  F8  F8  BI  = P5E_CPU0_P3_RX_BUF_DP<7>
  G1  G1  BI  = P5E_CPU0_P3_RX_BUF_DP<0>
  G2  G2  BI  = GND
  G3  G3  BI  = P5E_CPU0_P3_RX_BUF_DP<2>
  G4  G4  BI  = GND
  G5  G5  BI  = P5E_CPU0_P3_RX_BUF_DP<4>
  G6  G6  BI  = GND
  G7  G7  BI  = P5E_CPU0_P3_RX_BUF_DP<6>
  G8  G8  BI  = GND
  H1  H1  BI  = GND
  H2  H2  BI  = P5E_CPU0_P2_TX_BUF_C_DN<1>
  H3  H3  BI  = GND
  H4  H4  BI  = P5E_CPU0_P2_TX_BUF_C_DN<3>
  H5  H5  BI  = GND
  H6  H6  BI  = P5E_CPU0_P2_TX_BUF_C_DN<5>
  H7  H7  BI  = GND
  H8  H8  BI  = P5E_CPU0_P2_TX_BUF_C_DN<7>
  I1  I1  BI  = P5E_CPU0_P2_TX_BUF_C_DN<0>
  I2  I2  BI  = P5E_CPU0_P2_TX_BUF_C_DP<1>
  I3  I3  BI  = P5E_CPU0_P2_TX_BUF_C_DN<2>
  I4  I4  BI  = P5E_CPU0_P2_TX_BUF_C_DP<3>
  I5  I5  BI  = P5E_CPU0_P2_TX_BUF_C_DN<4>
  I6  I6  BI  = P5E_CPU0_P2_TX_BUF_C_DP<5>
  I7  I7  BI  = P5E_CPU0_P2_TX_BUF_C_DN<6>
  I8  I8  BI  = P5E_CPU0_P2_TX_BUF_C_DP<7>
  J1  J1  BI  = P5E_CPU0_P2_TX_BUF_C_DP<0>
  J2  J2  BI  = GND
  J3  J3  BI  = P5E_CPU0_P2_TX_BUF_C_DP<2>
  J4  J4  BI  = GND
  J5  J5  BI  = P5E_CPU0_P2_TX_BUF_C_DP<4>
  J6  J6  BI  = GND
  J7  J7  BI  = P5E_CPU0_P2_TX_BUF_C_DP<6>
  J8  J8  BI  = GND
  K1  K1  BI  = GND
  K2  K2  BI  = P5E_CPU0_P3_TX_BUF_C_DN<1>
  K3  K3  BI  = GND
  K4  K4  BI  = P5E_CPU0_P3_TX_BUF_C_DN<3>
  K5  K5  BI  = GND
  K6  K6  BI  = P5E_CPU0_P3_TX_BUF_C_DN<5>
  K7  K7  BI  = GND
  K8  K8  BI  = P5E_CPU0_P3_TX_BUF_C_DN<7>
  L1  L1  BI  = P5E_CPU0_P3_TX_BUF_C_DN<0>
  L2  L2  BI  = P5E_CPU0_P3_TX_BUF_C_DP<1>
  L3  L3  BI  = P5E_CPU0_P3_TX_BUF_C_DN<2>
  L4  L4  BI  = P5E_CPU0_P3_TX_BUF_C_DP<3>
  L5  L5  BI  = P5E_CPU0_P3_TX_BUF_C_DN<4>
  L6  L6  BI  = P5E_CPU0_P3_TX_BUF_C_DP<5>
  L7  L7  BI  = P5E_CPU0_P3_TX_BUF_C_DN<6>
  L8  L8  BI  = P5E_CPU0_P3_TX_BUF_C_DP<7>
  M1  M1  BI  = P5E_CPU0_P3_TX_BUF_C_DP<0>
  M2  M2  BI  = GND
  M3  M3  BI  = P5E_CPU0_P3_TX_BUF_C_DP<2>
  M4  M4  BI  = GND
  M5  M5  BI  = P5E_CPU0_P3_TX_BUF_C_DP<4>
  M6  M6  BI  = GND
  M7  M7  BI  = P5E_CPU0_P3_TX_BUF_C_DP<6>
  M8  M8  BI  = GND
  N1  N1  BI  = GND
  N2  N2  BI  = I3C_BMC_SWB_BUF_SDA
  N3  N3  BI  = GND
  N4  N4  BI  = I3C_BMC_SWB_BUF_SCL
  N5  N5  BI  = GND
  N6  N6  BI  = UART_BMC_BIC_RX
  N7  N7  BI  = GND
  N8  N8  BI  = UART_BMC_BIC_TX

J107  CONN112_10137002101LF  CONN112_10137002-101LF IO  pkg HSD_F112D8_P2W1-2_RDH  page 117
  A1  A1  BI  = NC_J107_A1
  A2  A2  BI  = GND
  A3  A3  BI  = NC_J107_A3
  A4  A4  BI  = GND
  A5  A5  BI  = NC_J107_A5
  A6  A6  BI  = GND
  A7  A7  BI  = SWB_HSC_PWRGD
  A8  A8  BI  = GND
  B1  B1  BI  = GND
  B2  B2  BI  = P5E_CPU0_P0_RX_BUF_DN<9>
  B3  B3  BI  = GND
  B4  B4  BI  = P5E_CPU0_P0_RX_BUF_DN<11>
  B5  B5  BI  = GND
  B6  B6  BI  = P5E_CPU0_P0_RX_BUF_DN<13>
  B7  B7  BI  = GND
  B8  B8  BI  = P5E_CPU0_P0_RX_BUF_DN<15>
  C1  C1  BI  = P5E_CPU0_P0_RX_BUF_DN<8>
  C2  C2  BI  = P5E_CPU0_P0_RX_BUF_DP<9>
  C3  C3  BI  = P5E_CPU0_P0_RX_BUF_DN<10>
  C4  C4  BI  = P5E_CPU0_P0_RX_BUF_DP<11>
  C5  C5  BI  = P5E_CPU0_P0_RX_BUF_DN<12>
  C6  C6  BI  = P5E_CPU0_P0_RX_BUF_DP<13>
  C7  C7  BI  = P5E_CPU0_P0_RX_BUF_DN<14>
  C8  C8  BI  = P5E_CPU0_P0_RX_BUF_DP<15>
  D1  D1  BI  = P5E_CPU0_P0_RX_BUF_DP<8>
  D2  D2  BI  = GND
  D3  D3  BI  = P5E_CPU0_P0_RX_BUF_DP<10>
  D4  D4  BI  = GND
  D5  D5  BI  = P5E_CPU0_P0_RX_BUF_DP<12>
  D6  D6  BI  = GND
  D7  D7  BI  = P5E_CPU0_P0_RX_BUF_DP<14>
  D8  D8  BI  = GND
  E1  E1  BI  = GND
  E2  E2  BI  = P5E_CPU0_P1_RX_BUF_DN<9>
  E3  E3  BI  = GND
  E4  E4  BI  = P5E_CPU0_P1_RX_BUF_DN<11>
  E5  E5  BI  = GND
  E6  E6  BI  = P5E_CPU0_P1_RX_BUF_DN<13>
  E7  E7  BI  = GND
  E8  E8  BI  = P5E_CPU0_P1_RX_BUF_DN<15>
  F1  F1  BI  = P5E_CPU0_P1_RX_BUF_DN<8>
  F2  F2  BI  = P5E_CPU0_P1_RX_BUF_DP<9>
  F3  F3  BI  = P5E_CPU0_P1_RX_BUF_DN<10>
  F4  F4  BI  = P5E_CPU0_P1_RX_BUF_DP<11>
  F5  F5  BI  = P5E_CPU0_P1_RX_BUF_DN<12>
  F6  F6  BI  = P5E_CPU0_P1_RX_BUF_DP<13>
  F7  F7  BI  = P5E_CPU0_P1_RX_BUF_DN<14>
  F8  F8  BI  = P5E_CPU0_P1_RX_BUF_DP<15>
  G1  G1  BI  = P5E_CPU0_P1_RX_BUF_DP<8>
  G2  G2  BI  = GND
  G3  G3  BI  = P5E_CPU0_P1_RX_BUF_DP<10>
  G4  G4  BI  = GND
  G5  G5  BI  = P5E_CPU0_P1_RX_BUF_DP<12>
  G6  G6  BI  = GND
  G7  G7  BI  = P5E_CPU0_P1_RX_BUF_DP<14>
  G8  G8  BI  = GND
  H1  H1  BI  = GND
  H2  H2  BI  = P5E_CPU0_P0_TX_BUF_C_DN<9>
  H3  H3  BI  = GND
  H4  H4  BI  = P5E_CPU0_P0_TX_BUF_C_DN<11>
  H5  H5  BI  = GND
  H6  H6  BI  = P5E_CPU0_P0_TX_BUF_C_DN<13>
  H7  H7  BI  = GND
  H8  H8  BI  = P5E_CPU0_P0_TX_BUF_C_DN<15>
  I1  I1  BI  = P5E_CPU0_P0_TX_BUF_C_DN<8>
  I2  I2  BI  = P5E_CPU0_P0_TX_BUF_C_DP<9>
  I3  I3  BI  = P5E_CPU0_P0_TX_BUF_C_DN<10>
  I4  I4  BI  = P5E_CPU0_P0_TX_BUF_C_DP<11>
  I5  I5  BI  = P5E_CPU0_P0_TX_BUF_C_DN<12>
  I6  I6  BI  = P5E_CPU0_P0_TX_BUF_C_DP<13>
  I7  I7  BI  = P5E_CPU0_P0_TX_BUF_C_DN<14>
  I8  I8  BI  = P5E_CPU0_P0_TX_BUF_C_DP<15>
  J1  J1  BI  = P5E_CPU0_P0_TX_BUF_C_DP<8>
  J2  J2  BI  = GND
  J3  J3  BI  = P5E_CPU0_P0_TX_BUF_C_DP<10>
  J4  J4  BI  = GND
  J5  J5  BI  = P5E_CPU0_P0_TX_BUF_C_DP<12>
  J6  J6  BI  = GND
  J7  J7  BI  = P5E_CPU0_P0_TX_BUF_C_DP<14>
  J8  J8  BI  = GND
  K1  K1  BI  = GND
  K2  K2  BI  = P5E_CPU0_P1_TX_BUF_C_DN<9>
  K3  K3  BI  = GND
  K4  K4  BI  = P5E_CPU0_P1_TX_BUF_C_DN<11>
  K5  K5  BI  = GND
  K6  K6  BI  = P5E_CPU0_P1_TX_BUF_C_DN<13>
  K7  K7  BI  = GND
  K8  K8  BI  = P5E_CPU0_P1_TX_BUF_C_DN<15>
  L1  L1  BI  = P5E_CPU0_P1_TX_BUF_C_DN<8>
  L2  L2  BI  = P5E_CPU0_P1_TX_BUF_C_DP<9>
  L3  L3  BI  = P5E_CPU0_P1_TX_BUF_C_DN<10>
  L4  L4  BI  = P5E_CPU0_P1_TX_BUF_C_DP<11>
  L5  L5  BI  = P5E_CPU0_P1_TX_BUF_C_DN<12>
  L6  L6  BI  = P5E_CPU0_P1_TX_BUF_C_DP<13>
  L7  L7  BI  = P5E_CPU0_P1_TX_BUF_C_DN<14>
  L8  L8  BI  = P5E_CPU0_P1_TX_BUF_C_DP<15>
  M1  M1  BI  = P5E_CPU0_P1_TX_BUF_C_DP<8>
  M2  M2  BI  = GND
  M3  M3  BI  = P5E_CPU0_P1_TX_BUF_C_DP<10>
  M4  M4  BI  = GND
  M5  M5  BI  = P5E_CPU0_P1_TX_BUF_C_DP<12>
  M6  M6  BI  = GND
  M7  M7  BI  = P5E_CPU0_P1_TX_BUF_C_DP<14>
  M8  M8  BI  = GND
  N1  N1  BI  = GND
  N2  N2  BI  = PRSNT_CABLE_SWB_B2_N
  N3  N3  BI  = GND
  N4  N4  BI  = NC_J107_N4
  N5  N5  BI  = GND
  N6  N6  BI  = NC_J107_N6
  N7  N7  BI  = GND
  N8  N8  BI  = SWB_HSC_EN_BUF

J108  CONN112_10137002101LF  CONN112_10137002-101LF IO  pkg HSD_F112D8_P2W1-2_RDH  page 118
  A1  A1  BI  = GPU_3V3IO_RSVD3_FFU
  A2  A2  BI  = GND
  A3  A3  BI  = PRSNT_CABLE_GPU_A2_N
  A4  A4  BI  = GND
  A5  A5  BI  = GPU_3V3IO_RSVD5_FFU
  A6  A6  BI  = GND
  A7  A7  BI  = GPU_FPGA_OVERT_N
  A8  A8  BI  = GND
  B1  B1  BI  = GND
  B2  B2  BI  = P5E_CPU0_P0_RX_BUF_DN<1>
  B3  B3  BI  = GND
  B4  B4  BI  = P5E_CPU0_P0_RX_BUF_DN<3>
  B5  B5  BI  = GND
  B6  B6  BI  = P5E_CPU0_P0_RX_BUF_DN<5>
  B7  B7  BI  = GND
  B8  B8  BI  = P5E_CPU0_P0_RX_BUF_DN<7>
  C1  C1  BI  = P5E_CPU0_P0_RX_BUF_DN<0>
  C2  C2  BI  = P5E_CPU0_P0_RX_BUF_DP<1>
  C3  C3  BI  = P5E_CPU0_P0_RX_BUF_DN<2>
  C4  C4  BI  = P5E_CPU0_P0_RX_BUF_DP<3>
  C5  C5  BI  = P5E_CPU0_P0_RX_BUF_DN<4>
  C6  C6  BI  = P5E_CPU0_P0_RX_BUF_DP<5>
  C7  C7  BI  = P5E_CPU0_P0_RX_BUF_DN<6>
  C8  C8  BI  = P5E_CPU0_P0_RX_BUF_DP<7>
  D1  D1  BI  = P5E_CPU0_P0_RX_BUF_DP<0>
  D2  D2  BI  = GND
  D3  D3  BI  = P5E_CPU0_P0_RX_BUF_DP<2>
  D4  D4  BI  = GND
  D5  D5  BI  = P5E_CPU0_P0_RX_BUF_DP<4>
  D6  D6  BI  = GND
  D7  D7  BI  = P5E_CPU0_P0_RX_BUF_DP<6>
  D8  D8  BI  = GND
  E1  E1  BI  = GND
  E2  E2  BI  = P5E_CPU0_P1_RX_BUF_DN<1>
  E3  E3  BI  = GND
  E4  E4  BI  = P5E_CPU0_P1_RX_BUF_DN<3>
  E5  E5  BI  = GND
  E6  E6  BI  = P5E_CPU0_P1_RX_BUF_DN<5>
  E7  E7  BI  = GND
  E8  E8  BI  = P5E_CPU0_P1_RX_BUF_DN<7>
  F1  F1  BI  = P5E_CPU0_P1_RX_BUF_DN<0>
  F2  F2  BI  = P5E_CPU0_P1_RX_BUF_DP<1>
  F3  F3  BI  = P5E_CPU0_P1_RX_BUF_DN<2>
  F4  F4  BI  = P5E_CPU0_P1_RX_BUF_DP<3>
  F5  F5  BI  = P5E_CPU0_P1_RX_BUF_DN<4>
  F6  F6  BI  = P5E_CPU0_P1_RX_BUF_DP<5>
  F7  F7  BI  = P5E_CPU0_P1_RX_BUF_DN<6>
  F8  F8  BI  = P5E_CPU0_P1_RX_BUF_DP<7>
  G1  G1  BI  = P5E_CPU0_P1_RX_BUF_DP<0>
  G2  G2  BI  = GND
  G3  G3  BI  = P5E_CPU0_P1_RX_BUF_DP<2>
  G4  G4  BI  = GND
  G5  G5  BI  = P5E_CPU0_P1_RX_BUF_DP<4>
  G6  G6  BI  = GND
  G7  G7  BI  = P5E_CPU0_P1_RX_BUF_DP<6>
  G8  G8  BI  = GND
  H1  H1  BI  = GND
  H2  H2  BI  = P5E_CPU0_P0_TX_BUF_C_DN<1>
  H3  H3  BI  = GND
  H4  H4  BI  = P5E_CPU0_P0_TX_BUF_C_DN<3>
  H5  H5  BI  = GND
  H6  H6  BI  = P5E_CPU0_P0_TX_BUF_C_DN<5>
  H7  H7  BI  = GND
  H8  H8  BI  = P5E_CPU0_P0_TX_BUF_C_DN<7>
  I1  I1  BI  = P5E_CPU0_P0_TX_BUF_C_DN<0>
  I2  I2  BI  = P5E_CPU0_P0_TX_BUF_C_DP<1>
  I3  I3  BI  = P5E_CPU0_P0_TX_BUF_C_DN<2>
  I4  I4  BI  = P5E_CPU0_P0_TX_BUF_C_DP<3>
  I5  I5  BI  = P5E_CPU0_P0_TX_BUF_C_DN<4>
  I6  I6  BI  = P5E_CPU0_P0_TX_BUF_C_DP<5>
  I7  I7  BI  = P5E_CPU0_P0_TX_BUF_C_DN<6>
  I8  I8  BI  = P5E_CPU0_P0_TX_BUF_C_DP<7>
  J1  J1  BI  = P5E_CPU0_P0_TX_BUF_C_DP<0>
  J2  J2  BI  = GND
  J3  J3  BI  = P5E_CPU0_P0_TX_BUF_C_DP<2>
  J4  J4  BI  = GND
  J5  J5  BI  = P5E_CPU0_P0_TX_BUF_C_DP<4>
  J6  J6  BI  = GND
  J7  J7  BI  = P5E_CPU0_P0_TX_BUF_C_DP<6>
  J8  J8  BI  = GND
  K1  K1  BI  = GND
  K2  K2  BI  = P5E_CPU0_P1_TX_BUF_C_DN<1>
  K3  K3  BI  = GND
  K4  K4  BI  = P5E_CPU0_P1_TX_BUF_C_DN<3>
  K5  K5  BI  = GND
  K6  K6  BI  = P5E_CPU0_P1_TX_BUF_C_DN<5>
  K7  K7  BI  = GND
  K8  K8  BI  = P5E_CPU0_P1_TX_BUF_C_DN<7>
  L1  L1  BI  = P5E_CPU0_P1_TX_BUF_C_DN<0>
  L2  L2  BI  = P5E_CPU0_P1_TX_BUF_C_DP<1>
  L3  L3  BI  = P5E_CPU0_P1_TX_BUF_C_DN<2>
  L4  L4  BI  = P5E_CPU0_P1_TX_BUF_C_DP<3>
  L5  L5  BI  = P5E_CPU0_P1_TX_BUF_C_DN<4>
  L6  L6  BI  = P5E_CPU0_P1_TX_BUF_C_DP<5>
  L7  L7  BI  = P5E_CPU0_P1_TX_BUF_C_DN<6>
  L8  L8  BI  = P5E_CPU0_P1_TX_BUF_C_DP<7>
  M1  M1  BI  = P5E_CPU0_P1_TX_BUF_C_DP<0>
  M2  M2  BI  = GND
  M3  M3  BI  = P5E_CPU0_P1_TX_BUF_C_DP<2>
  M4  M4  BI  = GND
  M5  M5  BI  = P5E_CPU0_P1_TX_BUF_C_DP<4>
  M6  M6  BI  = GND
  M7  M7  BI  = P5E_CPU0_P1_TX_BUF_C_DP<6>
  M8  M8  BI  = GND
  N1  N1  BI  = GND
  N2  N2  BI  = NC_J108_N2
  N3  N3  BI  = GND
  N4  N4  BI  = NC_J108_N4
  N5  N5  BI  = GND
  N6  N6  BI  = NC_J108_N6
  N7  N7  BI  = GND
  N8  N8  BI  = PRSNT_CABLE_GPU_A3_N
